(kicad_pcb
	(version 20260206)
	(generator "pcbnew")
	(generator_version "10.0")
	(general
		(thickness 1.6)
		(legacy_teardrops no)
	)
	(paper "A4")
	(title_block
		(title "12092022_DA0F0TFB6D0_F0T_FAN_BOARD_MP5048_D_brd_v02_OCP.brd")
		(comment 1 "Grand Teton / footprints 510-515 of 924")
	)
	(layers
		(0 "F.Cu" signal "TOP")
		(4 "In1.Cu" signal "GND")
		(6 "In2.Cu" signal "IN1")
		(8 "In3.Cu" signal "IN2")
		(10 "In4.Cu" signal "GND1")
		(2 "B.Cu" signal "BOTTOM")
		(9 "F.Adhes" user "F.Adhesive")
		(11 "B.Adhes" user "B.Adhesive")
		(13 "F.Paste" user "Package Geometry/Pastemask Top")
		(15 "B.Paste" user "Package Geometry/Pastemask Bottom")
		(5 "F.SilkS" user "Ref Des/Silkscreen Top")
		(7 "B.SilkS" user "Ref Des/Silkscreen Bottom")
		(1 "F.Mask" user "Board Geometry/Soldermask Top")
		(3 "B.Mask" user "Board Geometry/Soldermask Bottom")
		(17 "Dwgs.User" user "User.Drawings")
		(19 "Cmts.User" user "User.Comments")
		(21 "Eco1.User" user "User.Eco1")
		(23 "Eco2.User" user "User.Eco2")
		(25 "Edge.Cuts" user "Board Geometry/Outline")
		(27 "Margin" user)
		(31 "F.CrtYd" user "Package Geometry/Place Bound Top")
		(29 "B.CrtYd" user "Package Geometry/Place Bound Bottom")
		(35 "F.Fab" user "Ref Des/Assembly Top")
		(33 "B.Fab" user "Ref Des/Assembly Bottom")
	)
	(footprint ""
		(layer "F.Cu")
		(at 25.781 -300.99 180)
		(property "Reference" "U61"
			(at 1.00838 -1.94945 0)
			(unlocked yes)
			(layer "F.SilkS")
			(effects
				(font
					(size 0.7874 0.5842)
					(thickness 0.1524)
				)
				(justify left)
			)
		)
		(property "Value" ""
			(at 0 0 180)
			(layer "F.Fab")
			(effects
				(font
					(size 1.27 1.27)
				)
			)
		)
		(duplicate_pad_numbers_are_jumpers no)
		(fp_line
			(start 1.538478 1.150874)
			(end 1.538478 -1.150874)
			(stroke
				(width 0.1524)
				(type default)
			)
			(layer "F.SilkS")
		)
		(fp_line
			(start 1.538478 -1.150874)
			(end -1.538478 -1.150874)
			(stroke
				(width 0.1524)
				(type default)
			)
			(layer "F.SilkS")
		)
		(fp_line
			(start -1.538478 1.150874)
			(end 1.538478 1.150874)
			(stroke
				(width 0.1524)
				(type default)
			)
			(layer "F.SilkS")
		)
		(fp_line
			(start -1.538478 -1.150874)
			(end -1.538478 1.150874)
			(stroke
				(width 0.1524)
				(type default)
			)
			(layer "F.SilkS")
		)
		(fp_line
			(start 0.674878 1.100074)
			(end 0.674878 -1.100074)
			(stroke
				(width 0.1)
				(type default)
			)
			(layer "F.Fab")
		)
		(fp_line
			(start 0.674878 -1.100074)
			(end -0.674878 -1.100074)
			(stroke
				(width 0.1)
				(type default)
			)
			(layer "F.Fab")
		)
		(fp_line
			(start -0.674878 1.100074)
			(end 0.674878 1.100074)
			(stroke
				(width 0.1)
				(type default)
			)
			(layer "F.Fab")
		)
		(fp_line
			(start -0.674878 -1.100074)
			(end -0.674878 1.100074)
			(stroke
				(width 0.1)
				(type default)
			)
			(layer "F.Fab")
		)
		(pad "1" smd rect
			(at -0.94996 -0.649986 270)
			(size 0.7112 0.9144)
			(layers "F.Cu" "F.Mask" "F.Paste")
			(net "FAN_0_PWM_IL")
		)
		(pad "2" smd rect
			(at -0.94996 0.649986 270)
			(size 0.7112 0.9144)
			(layers "F.Cu" "F.Mask" "F.Paste")
			(net "FAN_0_PWM_OL")
		)
		(pad "3" smd rect
			(at 0.94996 0 270)
			(size 0.7112 0.9144)
			(layers "F.Cu" "F.Mask" "F.Paste")
			(net "FAN_0_PWM_BUF")
		)
	)
	(footprint ""
		(layer "F.Cu")
		(at 36.698428 -252.132846 180)
		(property "Reference" "R5418"
			(at 0 0 180)
			(layer "F.SilkS")
			(hide yes)
			(effects
				(font
					(size 1.27 1.27)
				)
			)
		)
		(property "Value" ""
			(at 0 0 180)
			(layer "F.Fab")
			(effects
				(font
					(size 1.27 1.27)
				)
			)
		)
		(duplicate_pad_numbers_are_jumpers no)
		(fp_line
			(start 0.7874 0.4064)
			(end -0.7874 0.4064)
			(stroke
				(width 0.1524)
				(type default)
			)
			(layer "F.SilkS")
		)
		(fp_line
			(start 0.7874 -0.4064)
			(end 0.7874 0.4064)
			(stroke
				(width 0.1524)
				(type default)
			)
			(layer "F.SilkS")
		)
		(fp_line
			(start -0.7874 0.4064)
			(end -0.7874 -0.4064)
			(stroke
				(width 0.1524)
				(type default)
			)
			(layer "F.SilkS")
		)
		(fp_line
			(start -0.7874 -0.4064)
			(end 0.7874 -0.4064)
			(stroke
				(width 0.1524)
				(type default)
			)
			(layer "F.SilkS")
		)
		(fp_line
			(start 0.67945 0.3048)
			(end 0.120396 0.3048)
			(stroke
				(width 0.1)
				(type default)
			)
			(layer "F.Fab")
		)
		(fp_line
			(start 0.67945 -0.3048)
			(end 0.67945 0.3048)
			(stroke
				(width 0.1)
				(type default)
			)
			(layer "F.Fab")
		)
		(fp_line
			(start 0.12065 -0.2794)
			(end 0.12065 -0.3048)
			(stroke
				(width 0.1)
				(type default)
			)
			(layer "F.Fab")
		)
		(fp_line
			(start 0.12065 -0.3048)
			(end 0.67945 -0.3048)
			(stroke
				(width 0.1)
				(type default)
			)
			(layer "F.Fab")
		)
		(fp_line
			(start 0.120396 0.3048)
			(end 0.120396 0.2794)
			(stroke
				(width 0.1)
				(type default)
			)
			(layer "F.Fab")
		)
		(fp_line
			(start 0.120396 0.2794)
			(end -0.12065 0.2794)
			(stroke
				(width 0.1)
				(type default)
			)
			(layer "F.Fab")
		)
		(fp_line
			(start -0.12065 0.3048)
			(end -0.67945 0.3048)
			(stroke
				(width 0.1)
				(type default)
			)
			(layer "F.Fab")
		)
		(fp_line
			(start -0.12065 0.2794)
			(end -0.12065 0.3048)
			(stroke
				(width 0.1)
				(type default)
			)
			(layer "F.Fab")
		)
		(fp_line
			(start -0.12065 -0.2794)
			(end 0.12065 -0.2794)
			(stroke
				(width 0.1)
				(type default)
			)
			(layer "F.Fab")
		)
		(fp_line
			(start -0.12065 -0.305054)
			(end -0.12065 -0.2794)
			(stroke
				(width 0.1)
				(type default)
			)
			(layer "F.Fab")
		)
		(fp_line
			(start -0.67945 0.3048)
			(end -0.67945 -0.305054)
			(stroke
				(width 0.1)
				(type default)
			)
			(layer "F.Fab")
		)
		(fp_line
			(start -0.67945 -0.305054)
			(end -0.12065 -0.305054)
			(stroke
				(width 0.1)
				(type default)
			)
			(layer "F.Fab")
		)
		(pad "1" smd circle
			(at -0.40005 0 180)
			(size 0 0)
			(layers "F.Cu" "F.Mask" "F.Paste")
			(net "FAN_1_PRESENT_R")
		)
		(pad "2" smd circle
			(at 0.40005 0 180)
			(size 0 0)
			(layers "F.Cu" "F.Mask" "F.Paste")
			(net "FAN_1_PRESENT")
		)
	)
	(footprint ""
		(layer "F.Cu")
		(at 29.845 -194.818 -90)
		(property "Reference" "C2092"
			(at 0 0 270)
			(layer "F.SilkS")
			(hide yes)
			(effects
				(font
					(size 1.27 1.27)
				)
			)
		)
		(property "Value" ""
			(at 0 0 270)
			(layer "F.Fab")
			(effects
				(font
					(size 1.27 1.27)
				)
			)
		)
		(duplicate_pad_numbers_are_jumpers no)
		(fp_line
			(start -0.7874 0.4064)
			(end -0.7874 -0.4064)
			(stroke
				(width 0.1524)
				(type default)
			)
			(layer "F.SilkS")
		)
		(fp_line
			(start 0.7874 0.4064)
			(end -0.7874 0.4064)
			(stroke
				(width 0.1524)
				(type default)
			)
			(layer "F.SilkS")
		)
		(fp_line
			(start -0.7874 -0.4064)
			(end 0.7874 -0.4064)
			(stroke
				(width 0.1524)
				(type default)
			)
			(layer "F.SilkS")
		)
		(fp_line
			(start 0.7874 -0.4064)
			(end 0.7874 0.4064)
			(stroke
				(width 0.1524)
				(type default)
			)
			(layer "F.SilkS")
		)
		(fp_line
			(start -0.67945 0.3048)
			(end -0.67945 -0.305054)
			(stroke
				(width 0.1)
				(type default)
			)
			(layer "F.Fab")
		)
		(fp_line
			(start -0.12065 0.3048)
			(end -0.67945 0.3048)
			(stroke
				(width 0.1)
				(type default)
			)
			(layer "F.Fab")
		)
		(fp_line
			(start 0.120396 0.3048)
			(end 0.120396 0.2794)
			(stroke
				(width 0.1)
				(type default)
			)
			(layer "F.Fab")
		)
		(fp_line
			(start 0.67945 0.3048)
			(end 0.120396 0.3048)
			(stroke
				(width 0.1)
				(type default)
			)
			(layer "F.Fab")
		)
		(fp_line
			(start -0.12065 0.2794)
			(end -0.12065 0.3048)
			(stroke
				(width 0.1)
				(type default)
			)
			(layer "F.Fab")
		)
		(fp_line
			(start 0.120396 0.2794)
			(end -0.12065 0.2794)
			(stroke
				(width 0.1)
				(type default)
			)
			(layer "F.Fab")
		)
		(fp_line
			(start -0.12065 -0.2794)
			(end 0.12065 -0.2794)
			(stroke
				(width 0.1)
				(type default)
			)
			(layer "F.Fab")
		)
		(fp_line
			(start 0.12065 -0.2794)
			(end 0.12065 -0.3048)
			(stroke
				(width 0.1)
				(type default)
			)
			(layer "F.Fab")
		)
		(fp_line
			(start 0.12065 -0.3048)
			(end 0.67945 -0.3048)
			(stroke
				(width 0.1)
				(type default)
			)
			(layer "F.Fab")
		)
		(fp_line
			(start 0.67945 -0.3048)
			(end 0.67945 0.3048)
			(stroke
				(width 0.1)
				(type default)
			)
			(layer "F.Fab")
		)
		(fp_line
			(start -0.67945 -0.305054)
			(end -0.12065 -0.305054)
			(stroke
				(width 0.1)
				(type default)
			)
			(layer "F.Fab")
		)
		(fp_line
			(start -0.12065 -0.305054)
			(end -0.12065 -0.2794)
			(stroke
				(width 0.1)
				(type default)
			)
			(layer "F.Fab")
		)
		(pad "1" smd circle
			(at -0.40005 0 270)
			(size 0 0)
			(layers "F.Cu" "F.Mask" "F.Paste")
			(net "P3V3_AUX")
		)
		(pad "2" smd circle
			(at 0.40005 0 270)
			(size 0 0)
			(layers "F.Cu" "F.Mask" "F.Paste")
			(net "GND")
		)
	)
	(footprint ""
		(layer "F.Cu")
		(at 18.415 -188.595 180)
		(property "Reference" "R308"
			(at 0 0 180)
			(layer "F.SilkS")
			(hide yes)
			(effects
				(font
					(size 1.27 1.27)
				)
			)
		)
		(property "Value" ""
			(at 0 0 180)
			(layer "F.Fab")
			(effects
				(font
					(size 1.27 1.27)
				)
			)
		)
		(duplicate_pad_numbers_are_jumpers no)
		(fp_line
			(start 0.7874 0.4064)
			(end -0.7874 0.4064)
			(stroke
				(width 0.1524)
				(type default)
			)
			(layer "F.SilkS")
		)
		(fp_line
			(start 0.7874 -0.4064)
			(end 0.7874 0.4064)
			(stroke
				(width 0.1524)
				(type default)
			)
			(layer "F.SilkS")
		)
		(fp_line
			(start -0.7874 0.4064)
			(end -0.7874 -0.4064)
			(stroke
				(width 0.1524)
				(type default)
			)
			(layer "F.SilkS")
		)
		(fp_line
			(start -0.7874 -0.4064)
			(end 0.7874 -0.4064)
			(stroke
				(width 0.1524)
				(type default)
			)
			(layer "F.SilkS")
		)
		(fp_line
			(start 0.67945 0.3048)
			(end 0.120396 0.3048)
			(stroke
				(width 0.1)
				(type default)
			)
			(layer "F.Fab")
		)
		(fp_line
			(start 0.67945 -0.3048)
			(end 0.67945 0.3048)
			(stroke
				(width 0.1)
				(type default)
			)
			(layer "F.Fab")
		)
		(fp_line
			(start 0.12065 -0.2794)
			(end 0.12065 -0.3048)
			(stroke
				(width 0.1)
				(type default)
			)
			(layer "F.Fab")
		)
		(fp_line
			(start 0.12065 -0.3048)
			(end 0.67945 -0.3048)
			(stroke
				(width 0.1)
				(type default)
			)
			(layer "F.Fab")
		)
		(fp_line
			(start 0.120396 0.3048)
			(end 0.120396 0.2794)
			(stroke
				(width 0.1)
				(type default)
			)
			(layer "F.Fab")
		)
		(fp_line
			(start 0.120396 0.2794)
			(end -0.12065 0.2794)
			(stroke
				(width 0.1)
				(type default)
			)
			(layer "F.Fab")
		)
		(fp_line
			(start -0.12065 0.3048)
			(end -0.67945 0.3048)
			(stroke
				(width 0.1)
				(type default)
			)
			(layer "F.Fab")
		)
		(fp_line
			(start -0.12065 0.2794)
			(end -0.12065 0.3048)
			(stroke
				(width 0.1)
				(type default)
			)
			(layer "F.Fab")
		)
		(fp_line
			(start -0.12065 -0.2794)
			(end 0.12065 -0.2794)
			(stroke
				(width 0.1)
				(type default)
			)
			(layer "F.Fab")
		)
		(fp_line
			(start -0.12065 -0.305054)
			(end -0.12065 -0.2794)
			(stroke
				(width 0.1)
				(type default)
			)
			(layer "F.Fab")
		)
		(fp_line
			(start -0.67945 0.3048)
			(end -0.67945 -0.305054)
			(stroke
				(width 0.1)
				(type default)
			)
			(layer "F.Fab")
		)
		(fp_line
			(start -0.67945 -0.305054)
			(end -0.12065 -0.305054)
			(stroke
				(width 0.1)
				(type default)
			)
			(layer "F.Fab")
		)
		(pad "1" smd circle
			(at -0.40005 0 180)
			(size 0 0)
			(layers "F.Cu" "F.Mask" "F.Paste")
			(net "P3V3_AUX")
		)
		(pad "2" smd circle
			(at 0.40005 0 180)
			(size 0 0)
			(layers "F.Cu" "F.Mask" "F.Paste")
			(net "FRU_WP_N")
		)
	)
	(footprint ""
		(layer "F.Cu")
		(at 34.798 -24.638)
		(property "Reference" "R5531"
			(at 0 0 0)
			(layer "F.SilkS")
			(hide yes)
			(effects
				(font
					(size 1.27 1.27)
				)
			)
		)
		(property "Value" ""
			(at 0 0 0)
			(layer "F.Fab")
			(effects
				(font
					(size 1.27 1.27)
				)
			)
		)
		(duplicate_pad_numbers_are_jumpers no)
		(fp_line
			(start -0.7874 -0.4064)
			(end 0.7874 -0.4064)
			(stroke
				(width 0.1524)
				(type default)
			)
			(layer "F.SilkS")
		)
		(fp_line
			(start -0.7874 0.4064)
			(end -0.7874 -0.4064)
			(stroke
				(width 0.1524)
				(type default)
			)
			(layer "F.SilkS")
		)
		(fp_line
			(start 0.7874 -0.4064)
			(end 0.7874 0.4064)
			(stroke
				(width 0.1524)
				(type default)
			)
			(layer "F.SilkS")
		)
		(fp_line
			(start 0.7874 0.4064)
			(end -0.7874 0.4064)
			(stroke
				(width 0.1524)
				(type default)
			)
			(layer "F.SilkS")
		)
		(fp_line
			(start -0.67945 -0.305054)
			(end -0.12065 -0.305054)
			(stroke
				(width 0.1)
				(type default)
			)
			(layer "F.Fab")
		)
		(fp_line
			(start -0.67945 0.3048)
			(end -0.67945 -0.305054)
			(stroke
				(width 0.1)
				(type default)
			)
			(layer "F.Fab")
		)
		(fp_line
			(start -0.12065 -0.305054)
			(end -0.12065 -0.2794)
			(stroke
				(width 0.1)
				(type default)
			)
			(layer "F.Fab")
		)
		(fp_line
			(start -0.12065 -0.2794)
			(end 0.12065 -0.2794)
			(stroke
				(width 0.1)
				(type default)
			)
			(layer "F.Fab")
		)
		(fp_line
			(start -0.12065 0.2794)
			(end -0.12065 0.3048)
			(stroke
				(width 0.1)
				(type default)
			)
			(layer "F.Fab")
		)
		(fp_line
			(start -0.12065 0.3048)
			(end -0.67945 0.3048)
			(stroke
				(width 0.1)
				(type default)
			)
			(layer "F.Fab")
		)
		(fp_line
			(start 0.120396 0.2794)
			(end -0.12065 0.2794)
			(stroke
				(width 0.1)
				(type default)
			)
			(layer "F.Fab")
		)
		(fp_line
			(start 0.120396 0.3048)
			(end 0.120396 0.2794)
			(stroke
				(width 0.1)
				(type default)
			)
			(layer "F.Fab")
		)
		(fp_line
			(start 0.12065 -0.3048)
			(end 0.67945 -0.3048)
			(stroke
				(width 0.1)
				(type default)
			)
			(layer "F.Fab")
		)
		(fp_line
			(start 0.12065 -0.2794)
			(end 0.12065 -0.3048)
			(stroke
				(width 0.1)
				(type default)
			)
			(layer "F.Fab")
		)
		(fp_line
			(start 0.67945 -0.3048)
			(end 0.67945 0.3048)
			(stroke
				(width 0.1)
				(type default)
			)
			(layer "F.Fab")
		)
		(fp_line
			(start 0.67945 0.3048)
			(end 0.120396 0.3048)
			(stroke
				(width 0.1)
				(type default)
			)
			(layer "F.Fab")
		)
		(pad "1" smd rect
			(at -0.40005 0 180)
			(size 0.4572 0.508)
			(layers "F.Cu" "F.Mask" "F.Paste")
			(net "P12V_LED_FAN3")
		)
		(pad "2" smd rect
			(at 0.40005 0 180)
			(size 0.4572 0.508)
			(layers "F.Cu" "F.Mask" "F.Paste")
			(net "FAN_3_FAIL_LED_R_N")
		)
	)
	(footprint ""
		(layer "F.Cu")
		(at 15.377922 -17.866868 180)
		(property "Reference" "D242"
			(at 5.852922 -0.436118 0)
			(unlocked yes)
			(layer "F.SilkS")
			(effects
				(font
					(size 0.635 0.4064)
					(thickness 0.1524)
				)
				(justify left)
			)
		)
		(property "Value" ""
			(at 0 0 180)
			(layer "F.Fab")
			(effects
				(font
					(size 1.27 1.27)
				)
			)
		)
		(duplicate_pad_numbers_are_jumpers no)
		(fp_line
			(start 0.94488 0.450088)
			(end 0.94488 -0.450088)
			(stroke
				(width 0.1524)
				(type default)
			)
			(layer "F.SilkS")
		)
		(fp_line
			(start 0.94488 -0.450088)
			(end -0.854964 -0.450088)
			(stroke
				(width 0.1524)
				(type default)
			)
			(layer "F.SilkS")
		)
		(fp_line
			(start 0.870458 -0.2794)
			(end 0.845058 0.4064)
			(stroke
				(width 0.1524)
				(type default)
			)
			(layer "F.SilkS")
		)
		(fp_line
			(start 0.845058 0.4064)
			(end 0.845058 -0.381)
			(stroke
				(width 0.1524)
				(type default)
			)
			(layer "F.SilkS")
		)
		(fp_line
			(start -0.854964 0.450088)
			(end 0.925068 0.450088)
			(stroke
				(width 0.1524)
				(type default)
			)
			(layer "F.SilkS")
		)
		(fp_line
			(start -0.854964 -0.450088)
			(end -0.854964 0.450088)
			(stroke
				(width 0.1524)
				(type default)
			)
			(layer "F.SilkS")
		)
		(fp_line
			(start 0.54991 0.350012)
			(end 0.54991 -0.350012)
			(stroke
				(width 0.1)
				(type default)
			)
			(layer "F.Fab")
		)
		(fp_line
			(start 0.54991 -0.350012)
			(end -0.54991 -0.350012)
			(stroke
				(width 0.1)
				(type default)
			)
			(layer "F.Fab")
		)
		(fp_line
			(start -0.54991 0.350012)
			(end 0.54991 0.350012)
			(stroke
				(width 0.1)
				(type default)
			)
			(layer "F.Fab")
		)
		(fp_line
			(start -0.54991 -0.350012)
			(end -0.54991 0.350012)
			(stroke
				(width 0.1)
				(type default)
			)
			(layer "F.Fab")
		)
		(fp_text user "-"
			(at 2.296922 0.262382 0)
			(unlocked yes)
			(layer "F.SilkS")
			(effects
				(font
					(size 1.905 1.4224)
					(thickness 0.1524)
				)
				(justify left)
			)
		)
		(fp_text user "+"
			(at -0.624078 0.262382 0)
			(unlocked yes)
			(layer "F.SilkS")
			(effects
				(font
					(size 1.905 1.4224)
					(thickness 0.1524)
				)
				(justify left)
			)
		)
		(fp_text user "-"
			(at 2.48539 0.239014 0)
			(unlocked yes)
			(layer "F.Fab")
			(effects
				(font
					(size 1.905 1.4224)
					(thickness 0.1524)
				)
				(justify left)
			)
		)
		(fp_text user "+"
			(at -0.808228 0.239014 0)
			(unlocked yes)
			(layer "F.Fab")
			(effects
				(font
					(size 1.905 1.4224)
					(thickness 0.1524)
				)
				(justify left)
			)
		)
		(pad "A" smd rect
			(at -0.424942 0 180)
			(size 0.5588 0.6096)
			(layers "F.Cu" "F.Mask" "F.Paste")
			(net "GND")
		)
		(pad "C" smd rect
			(at 0.424942 0)
			(size 0.5588 0.6096)
			(layers "F.Cu" "F.Mask" "F.Paste")
			(net "FAN_4_TACH_IL_D")
		)
	)
)
